(kicad_pcb
	(version 20260206)
	(generator "pcbnew")
	(generator_version "10.0")
	(general
		(thickness 1.6)
		(legacy_teardrops no)
	)
	(paper "A4")
	(title_block
		(title "4HDD Backplane_Layout.brd")
		(comment 1 "Tioga Pass / footprints 96-97 of 97")
	)
	(layers
		(0 "F.Cu" signal "TOP")
		(4 "In1.Cu" signal "L2GND")
		(6 "In2.Cu" signal "L3")
		(8 "In3.Cu" signal "L4")
		(10 "In4.Cu" signal "L5GND")
		(2 "B.Cu" signal "BOTTOM")
		(9 "F.Adhes" user "F.Adhesive")
		(11 "B.Adhes" user "B.Adhesive")
		(13 "F.Paste" user "Package Geometry/Pastemask Top")
		(15 "B.Paste" user "Package Geometry/Pastemask Bottom")
		(5 "F.SilkS" user "Ref Des/Silkscreen Top")
		(7 "B.SilkS" user "Ref Des/Silkscreen Bottom")
		(1 "F.Mask" user "Board Geometry/Soldermask Top")
		(3 "B.Mask" user "Board Geometry/Soldermask Bottom")
		(17 "Dwgs.User" user "User.Drawings")
		(19 "Cmts.User" user "User.Comments")
		(21 "Eco1.User" user "User.Eco1")
		(23 "Eco2.User" user "User.Eco2")
		(25 "Edge.Cuts" user "Board Geometry/Outline")
		(27 "Margin" user)
		(31 "F.CrtYd" user "Package Geometry/Place Bound Top")
		(29 "B.CrtYd" user "Package Geometry/Place Bound Bottom")
		(35 "F.Fab" user "Ref Des/Assembly Top")
		(33 "B.Fab" user "Ref Des/Assembly Bottom")
	)
	(footprint ""
		(layer "B.Cu")
		(at 127.679958 -22.049994)
		(property "Reference" "CN2"
			(at 0 0 0)
			(layer "B.SilkS")
			(hide yes)
			(effects
				(font
					(size 1.27 1.27)
				)
				(justify mirror)
			)
		)
		(property "Value" "AMP-CON4-S7-GP"
			(at -3.5306 -4.9784 0)
			(unlocked yes)
			(layer "B.Fab")
			(hide yes)
			(effects
				(font
					(size 1.016 1.016)
					(thickness 0.1524)
				)
				(justify mirror)
			)
		)
		(property "Device Type" "G88MPB04102CEU"
			(at -3.5306 -6.5024 0)
			(unlocked yes)
			(layer "B.Fab")
			(hide yes)
			(effects
				(font
					(size 1.016 1.016)
					(thickness 0.1524)
				)
				(justify mirror)
			)
		)
		(duplicate_pad_numbers_are_jumpers no)
		(fp_line
			(start -8.509 -2.286)
			(end -7.239 -2.286)
			(stroke
				(width 0.4064)
				(type default)
			)
			(layer "B.SilkS")
		)
		(fp_line
			(start -8.509 -1.016)
			(end -8.509 -2.286)
			(stroke
				(width 0.4064)
				(type default)
			)
			(layer "B.SilkS")
		)
		(fp_line
			(start -8.382 -2.159)
			(end -8.382 2.8448)
			(stroke
				(width 0.1524)
				(type default)
			)
			(layer "B.SilkS")
		)
		(fp_line
			(start -8.382 2.8448)
			(end 8.382 2.8448)
			(stroke
				(width 0.1524)
				(type default)
			)
			(layer "B.SilkS")
		)
		(fp_line
			(start -1.7526 -3.3528)
			(end -1.7526 -2.159)
			(stroke
				(width 0.1524)
				(type default)
			)
			(layer "B.SilkS")
		)
		(fp_line
			(start -1.7526 -2.159)
			(end -8.382 -2.159)
			(stroke
				(width 0.1524)
				(type default)
			)
			(layer "B.SilkS")
		)
		(fp_line
			(start 1.7526 -3.3528)
			(end -1.7526 -3.3528)
			(stroke
				(width 0.1524)
				(type default)
			)
			(layer "B.SilkS")
		)
		(fp_line
			(start 1.7526 -2.159)
			(end 1.7526 -3.3528)
			(stroke
				(width 0.1524)
				(type default)
			)
			(layer "B.SilkS")
		)
		(fp_line
			(start 8.382 -2.159)
			(end 1.7526 -2.159)
			(stroke
				(width 0.1524)
				(type default)
			)
			(layer "B.SilkS")
		)
		(fp_line
			(start 8.382 2.8448)
			(end 8.382 -2.159)
			(stroke
				(width 0.1524)
				(type default)
			)
			(layer "B.SilkS")
		)
		(fp_circle
			(center -4.500118 0)
			(end -3.242818 0)
			(stroke
				(width 0.3048)
				(type default)
			)
			(fill no)
			(layer "B.SilkS")
		)
		(fp_circle
			(center -1.500124 0)
			(end -0.242824 0)
			(stroke
				(width 0.3048)
				(type default)
			)
			(fill no)
			(layer "B.SilkS")
		)
		(fp_circle
			(center 1.500124 0)
			(end 2.757424 0)
			(stroke
				(width 0.3048)
				(type default)
			)
			(fill no)
			(layer "B.SilkS")
		)
		(fp_circle
			(center 4.500118 0)
			(end 5.757418 0)
			(stroke
				(width 0.3048)
				(type default)
			)
			(fill no)
			(layer "B.SilkS")
		)
		(fp_poly
			(pts
				(xy 7.8232 -1.905) (xy 1.4986 -1.905) (xy 1.4986 -3.0988) (xy -1.4986 -3.0988) (xy -1.4986 -1.905)
				(xy -7.8232 -1.905) (xy -7.8232 2.4638) (xy 7.8232 2.4638)
			)
			(stroke
				(width 0)
				(type default)
			)
			(fill no)
			(layer "B.CrtYd")
		)
		(fp_poly
			(pts
				(xy 8.636 3.0988) (xy 8.636 -2.413) (xy 2.0066 -2.413) (xy 2.0066 -3.6068) (xy -2.0066 -3.6068)
				(xy -2.0066 -2.413) (xy -8.636 -2.413) (xy -8.636 -0.00635) (xy -7.8232 -0.00635) (xy -7.8232 -1.905)
				(xy -1.4986 -1.905) (xy -1.4986 -3.0988) (xy 1.4986 -3.0988) (xy 1.4986 -1.905) (xy 7.8232 -1.905)
				(xy 7.8232 2.4638) (xy -7.8232 2.4638) (xy -7.8232 0.00635) (xy -8.636 0.00635) (xy -8.636 3.0988)
			)
			(stroke
				(width 0)
				(type default)
			)
			(fill no)
			(layer "B.CrtYd")
		)
		(fp_poly
			(pts
				(xy 8.636 3.0988) (xy 8.636 -2.413) (xy 2.0066 -2.413) (xy 2.0066 -3.6068) (xy -2.0066 -3.6068)
				(xy -2.0066 -2.413) (xy -8.636 -2.413) (xy -8.636 3.0988)
			)
			(stroke
				(width 0)
				(type default)
			)
			(fill no)
			(layer "B.Fab")
		)
		(pad "" np_thru_hole circle
			(at -7.500112 1.960118 180)
			(size 0.254 0.254)
			(drill 1.27)
			(layers "*.Cu" "*.Mask")
			(clearance 0.8636)
			(thermal_gap 0.8636)
		)
		(pad "" np_thru_hole circle
			(at 7.500112 1.960118 180)
			(size 0.254 0.254)
			(drill 1.27)
			(layers "*.Cu" "*.Mask")
			(clearance 0.8636)
			(thermal_gap 0.8636)
		)
		(pad "1" thru_hole circle
			(at -4.500118 0 180)
			(size 1.8034 1.8034)
			(drill 1.1684)
			(layers "*.Cu" "*.Mask")
			(remove_unused_layers no)
			(net "P12V")
			(clearance 0.1905)
			(thermal_gap 0.1905)
		)
		(pad "2" thru_hole circle
			(at -1.500124 0 180)
			(size 1.8034 1.8034)
			(drill 1.1684)
			(layers "*.Cu" "*.Mask")
			(remove_unused_layers no)
			(net "GND")
			(clearance 0.1905)
			(thermal_gap 0.1905)
		)
		(pad "3" thru_hole circle
			(at 1.500124 0 180)
			(size 1.8034 1.8034)
			(drill 1.1684)
			(layers "*.Cu" "*.Mask")
			(remove_unused_layers no)
			(net "GND")
			(clearance 0.1905)
			(thermal_gap 0.1905)
		)
		(pad "4" thru_hole circle
			(at 4.500118 0 180)
			(size 1.8034 1.8034)
			(drill 1.1684)
			(layers "*.Cu" "*.Mask")
			(remove_unused_layers no)
			(net "P5V")
			(clearance 0.1905)
			(thermal_gap 0.1905)
		)
		(zone
			(layers "F.Cu" "B.Cu" "In1.Cu" "In2.Cu" "In3.Cu" "In4.Cu")
			(hatch none 0.5)
			(connect_pads
				(clearance 0)
			)
			(min_thickness 0.25)
			(keepout
				(tracks not_allowed)
				(vias allowed)
				(pads allowed)
				(copperpour not_allowed)
				(footprints allowed)
			)
			(placement
				(enabled no)
				(sheetname "")
			)
			(fill
				(thermal_gap 0.5)
				(thermal_bridge_width 0.5)
				(island_removal_mode 0)
			)
			(polygon
				(pts
					(arc
						(start 121.119646 -20.089876)
						(mid 119.240046 -20.089876)
						(end 121.119646 -20.089876)
					)
				)
			)
		)
		(zone
			(layers "F.Cu" "B.Cu" "In1.Cu" "In2.Cu" "In3.Cu" "In4.Cu")
			(hatch none 0.5)
			(connect_pads
				(clearance 0)
			)
			(min_thickness 0.25)
			(keepout
				(tracks not_allowed)
				(vias allowed)
				(pads allowed)
				(copperpour not_allowed)
				(footprints allowed)
			)
			(placement
				(enabled no)
				(sheetname "")
			)
			(fill
				(thermal_gap 0.5)
				(thermal_bridge_width 0.5)
				(island_removal_mode 0)
			)
			(polygon
				(pts
					(arc
						(start 136.11987 -20.089876)
						(mid 134.24027 -20.089876)
						(end 136.11987 -20.089876)
					)
				)
			)
		)
	)
	(footprint ""
		(layer "B.Cu")
		(at 81.026 -39.878 90)
		(property "Reference" "U9"
			(at 0 0 90)
			(layer "B.SilkS")
			(hide yes)
			(effects
				(font
					(size 1.27 1.27)
				)
				(justify mirror)
			)
		)
		(property "Value" "P2003EVG-GP"
			(at 0 -11.1252 90)
			(unlocked yes)
			(layer "B.Fab")
			(hide yes)
			(effects
				(font
					(size 1.016 1.016)
					(thickness 0.1524)
				)
				(justify mirror)
			)
		)
		(property "Device Type" "SOIC8H79"
			(at 0 -12.6492 90)
			(unlocked yes)
			(layer "B.Fab")
			(hide yes)
			(effects
				(font
					(size 1.016 1.016)
					(thickness 0.1524)
				)
				(justify mirror)
			)
		)
		(duplicate_pad_numbers_are_jumpers no)
		(fp_line
			(start 2.7432 -1.4224)
			(end 2.7432 1.4224)
			(stroke
				(width 0.1524)
				(type default)
			)
			(layer "B.SilkS")
		)
		(fp_line
			(start -2.1336 -1.4224)
			(end 2.7432 -1.4224)
			(stroke
				(width 0.1524)
				(type default)
			)
			(layer "B.SilkS")
		)
		(fp_line
			(start 2.7432 -0.508)
			(end 2.2352 0)
			(stroke
				(width 0.1524)
				(type default)
			)
			(layer "B.SilkS")
		)
		(fp_line
			(start 2.2352 0)
			(end 2.7432 0.508)
			(stroke
				(width 0.1524)
				(type default)
			)
			(layer "B.SilkS")
		)
		(fp_line
			(start 2.7432 1.4224)
			(end -2.1336 1.4224)
			(stroke
				(width 0.1524)
				(type default)
			)
			(layer "B.SilkS")
		)
		(fp_line
			(start -2.1336 1.4224)
			(end -2.1336 -1.4224)
			(stroke
				(width 0.1524)
				(type default)
			)
			(layer "B.SilkS")
		)
		(fp_line
			(start 2.6162 3.429)
			(end 2.6162 1.4732)
			(stroke
				(width 0.4064)
				(type default)
			)
			(layer "B.SilkS")
		)
		(fp_poly
			(pts
				(xy -2.2098 -1.4224) (xy -2.2098 1.4224) (xy 2.2225 1.4224) (xy 2.2225 -1.4224)
			)
			(stroke
				(width 0)
				(type default)
			)
			(fill yes)
			(layer "B.SilkS")
		)
		(fp_rect
			(start 2.4511 2.9972)
			(end -2.4511 -2.9972)
			(stroke
				(width 0)
				(type default)
			)
			(fill no)
			(layer "B.CrtYd")
		)
		(fp_poly
			(pts
				(xy 2.8194 3.6322) (xy 2.8194 -3.6322) (xy -2.8194 -3.6322) (xy -2.8194 -2.2987) (xy -2.4511 -2.2987)
				(xy -2.4511 -2.9972) (xy 2.4511 -2.9972) (xy 2.4511 2.9972) (xy -2.4511 2.9972) (xy -2.4511 -2.286)
				(xy -2.8194 -2.286) (xy -2.8194 3.6322)
			)
			(stroke
				(width 0)
				(type default)
			)
			(fill no)
			(layer "B.CrtYd")
		)
		(fp_rect
			(start 2.8194 3.6322)
			(end -2.8194 -3.6322)
			(stroke
				(width 0)
				(type default)
			)
			(fill no)
			(layer "B.Fab")
		)
		(pad "1" smd rect
			(at 1.905 2.54 270)
			(size 0.635 1.651)
			(layers "B.Cu" "B.Mask" "B.Paste")
			(net "P12V")
		)
		(pad "2" smd rect
			(at 0.635 2.54 270)
			(size 0.635 1.651)
			(layers "B.Cu" "B.Mask" "B.Paste")
			(net "P12V")
		)
		(pad "3" smd rect
			(at -0.635 2.54 270)
			(size 0.635 1.651)
			(layers "B.Cu" "B.Mask" "B.Paste")
			(net "P12V")
		)
		(pad "4" smd rect
			(at -1.905 2.54 270)
			(size 0.635 1.651)
			(layers "B.Cu" "B.Mask" "B.Paste")
			(net "SW_SW_R_N_0")
		)
		(pad "5" smd rect
			(at -1.905 -2.54 270)
			(size 0.635 1.651)
			(layers "B.Cu" "B.Mask" "B.Paste")
			(net "P12V_SW_R")
		)
		(pad "6" smd rect
			(at -0.635 -2.54 270)
			(size 0.635 1.651)
			(layers "B.Cu" "B.Mask" "B.Paste")
			(net "P12V_SW_R")
		)
		(pad "7" smd rect
			(at 0.635 -2.54 270)
			(size 0.635 1.651)
			(layers "B.Cu" "B.Mask" "B.Paste")
			(net "P12V_SW_R")
		)
		(pad "8" smd rect
			(at 1.905 -2.54 270)
			(size 0.635 1.651)
			(layers "B.Cu" "B.Mask" "B.Paste")
			(net "P12V_SW_R")
		)
	)
)
